(kicad_pcb
	(version 20221018)
	(generator pcbnew)
	(general
    (thickness 1.62)
  )
	(paper "A4")
	(title_block
    (title "ECP5 - Datacenter Secure Control Module (DC-SCM)")
    (date "2024-07-01")
    (rev "1.2.1")
		(comment 9 "footprints 102-110 of 506")
	)
	(layers
    (0 "F.Cu" signal)
    (1 "In1.Cu" power)
    (2 "In2.Cu" signal)
    (3 "In3.Cu" power)
    (4 "In4.Cu" power)
    (5 "In5.Cu" signal)
    (6 "In6.Cu" power)
    (31 "B.Cu" signal)
    (32 "B.Adhes" user "B.Adhesive")
    (33 "F.Adhes" user "F.Adhesive")
    (34 "B.Paste" user)
    (35 "F.Paste" user)
    (36 "B.SilkS" user "B.Silkscreen")
    (37 "F.SilkS" user "F.Silkscreen")
    (38 "B.Mask" user)
    (39 "F.Mask" user)
    (40 "Dwgs.User" user "User.Drawings")
    (41 "Cmts.User" user "User.Comments")
    (42 "Eco1.User" user "User.Eco1")
    (43 "Eco2.User" user "User.Eco2")
    (44 "Edge.Cuts" user)
    (45 "Margin" user)
    (46 "B.CrtYd" user "B.Courtyard")
    (47 "F.CrtYd" user "F.Courtyard")
    (48 "B.Fab" user)
    (49 "F.Fab" user)
  )
	(footprint "antmicro-footprints:C_0402_1005Metric" (layer "F.Cu")
    (at 74 62.35)
    (descr "Capacitor SMD 0402")
    (tags "capacitor SMD 0402")
    (property "Author" "Antmicro")
    (property "Dielectric" "")
    (property "License" "Apache-2.0")
    (property "MPN" "CGA2B3X7S2A472K050BB")
    (property "Manufacturer" "TDK")
    (property "Public" "False")
    (property "Sheetfile" "power-supply.kicad_sch")
    (property "Sheetname" "Power supply")
    (property "Val" "4n7")
    (property "Voltage" "")
    (property "ki_description" "SMD Multilayer Ceramic Capacitor, 4700 pF, 100 V, 0402 [1005 Metric], ± 10%, X7S, CGA")
    (property "ki_keywords" "0402, SMT, CAPACITOR, PASSIVE, CERAMIC, MLCC")
    (attr smd)
    (fp_text reference "C102" (at -0.18 2.615) (layer "F.SilkS")
        (effects (font (size 0.7 0.7) (thickness 0.127)))
    )
    (fp_text value "C_4n7_0402" (at 0 1.17) (layer "F.Fab")
        (effects (font (size 1 1) (thickness 0.15)))
    )
    (fp_text user "License: Apache-2.0" (at -0.939 5.799) (layer "F.Fab") hide
        (effects (font (size 0.7 0.7) (thickness 0.15)) (justify left bottom))
    )
    (fp_text user "Author: Antmicro" (at -0.939 3.399) (layer "F.Fab") hide
        (effects (font (size 0.7 0.7) (thickness 0.15)) (justify left bottom))
    )
    (fp_text user "${REFERENCE}" (at 0 0) (layer "F.Fab")
        (effects (font (size 0.25 0.25) (thickness 0.04)))
    )
    (fp_rect (start -0.925 -0.47) (end 0.925 0.47)
      (stroke (width 0.05) (type default)) (fill none) (layer "F.CrtYd"))
    (fp_line (start -0.494 -0.25) (end 0.504 -0.25)
      (stroke (width 0.15) (type solid)) (layer "F.Fab"))
    (fp_line (start -0.494 0.248) (end -0.494 -0.25)
      (stroke (width 0.15) (type solid)) (layer "F.Fab"))
    (fp_line (start 0.504 -0.25) (end 0.504 0.248)
      (stroke (width 0.15) (type solid)) (layer "F.Fab"))
    (fp_line (start 0.504 0.248) (end -0.494 0.248)
      (stroke (width 0.15) (type solid)) (layer "F.Fab"))
    (pad "1" smd roundrect (at -0.48 0) (size 0.59 0.64) (layers "F.Cu" "F.Paste" "F.Mask") (roundrect_rratio 0.25)
      (net 1 "GND") (pintype "passive"))
    (pad "2" smd roundrect (at 0.48 0) (size 0.59 0.64) (layers "F.Cu" "F.Paste" "F.Mask") (roundrect_rratio 0.25)
      (net 233 "Net-(C102-Pad2)") (pintype "passive"))
  )
	(footprint "antmicro-footprints:R_0402_1005Metric" (layer "F.Cu")
    (at 75.55 62.9 90)
    (descr "Resistor SMD 0402")
    (tags "resistor SMD 0402")
    (property "Author" "Antmicro")
    (property "License" "Apache-2.0")
    (property "MPN" "CR0402-FX-1692GLF")
    (property "Manufacturer" "Bourns")
    (property "Public" "False")
    (property "Sheetfile" "power-supply.kicad_sch")
    (property "Sheetname" "Power supply")
    (property "Tolerance" "1%")
    (property "Val" "16k9")
    (property "ki_description" "SMD Chip Resistor, Ceramic, 16.9 kohm, ± 1%, 62.5 mW, 0402 [1005 Metric], Thick Film")
    (property "ki_keywords" "0402, SMT, RESISTOR, PASSIVE")
    (attr smd)
    (fp_text reference "R90" (at -3.445 -0.07 90) (layer "F.SilkS")
        (effects (font (size 0.7 0.7) (thickness 0.127)))
    )
    (fp_text value "R_16k9_0402" (at 0 1.17 90) (layer "F.Fab")
        (effects (font (size 1 1) (thickness 0.15)))
    )
    (fp_text user "${REFERENCE}" (at 0 0 90) (layer "F.Fab")
        (effects (font (size 0.25 0.25) (thickness 0.04)))
    )
    (fp_text user "Author: Antmicro" (at -0.95 4.169 90) (layer "F.Fab") hide
        (effects (font (size 0.7 0.7) (thickness 0.15)) (justify left bottom))
    )
    (fp_text user "License: Apache-2.0" (at -0.95 5.169 90) (layer "F.Fab") hide
        (effects (font (size 0.7 0.7) (thickness 0.15)) (justify left bottom))
    )
    (fp_rect (start -0.925 -0.47) (end 0.925 0.47)
      (stroke (width 0.05) (type default)) (fill none) (layer "F.CrtYd"))
    (fp_rect (start -0.5 -0.25) (end 0.5 0.25)
      (stroke (width 0.15) (type solid)) (fill none) (layer "F.Fab"))
    (pad "1" smd roundrect (at -0.48 0 90) (size 0.59 0.64) (layers "F.Cu" "F.Paste" "F.Mask") (roundrect_rratio 0.25)
      (net 781 "Net-(U15-COMP)") (pintype "passive"))
    (pad "2" smd roundrect (at 0.48 0 90) (size 0.59 0.64) (layers "F.Cu" "F.Paste" "F.Mask") (roundrect_rratio 0.25)
      (net 233 "Net-(C102-Pad2)") (pintype "passive"))
  )
	(footprint "antmicro-footprints:R_0402_1005Metric" (layer "F.Cu")
    (at 77.145 62.255)
    (descr "Resistor SMD 0402")
    (tags "resistor SMD 0402")
    (property "Author" "Antmicro")
    (property "License" "Apache-2.0")
    (property "MPN" "CR0402-FX-1022GLF")
    (property "Manufacturer" "Bourns")
    (property "Public" "False")
    (property "Sheetfile" "power-supply.kicad_sch")
    (property "Sheetname" "Power supply")
    (property "Tolerance" "1%")
    (property "Val" "10k2")
    (property "ki_description" "SMD Chip Resistor")
    (property "ki_keywords" "0402, SMT, RESISTOR, PASSIVE")
    (attr smd)
    (fp_text reference "R97" (at 0.165 -1.88) (layer "F.SilkS")
        (effects (font (size 0.7 0.7) (thickness 0.127)))
    )
    (fp_text value "R_10k2_0402" (at 0 1.17) (layer "F.Fab")
        (effects (font (size 1 1) (thickness 0.15)))
    )
    (fp_text user "License: Apache-2.0" (at -0.95 5.169) (layer "F.Fab") hide
        (effects (font (size 0.7 0.7) (thickness 0.15)) (justify left bottom))
    )
    (fp_text user "Author: Antmicro" (at -0.95 4.169) (layer "F.Fab") hide
        (effects (font (size 0.7 0.7) (thickness 0.15)) (justify left bottom))
    )
    (fp_text user "${REFERENCE}" (at 0 0) (layer "F.Fab")
        (effects (font (size 0.25 0.25) (thickness 0.04)))
    )
    (fp_rect (start -0.925 -0.47) (end 0.925 0.47)
      (stroke (width 0.05) (type default)) (fill none) (layer "F.CrtYd"))
    (fp_rect (start -0.5 -0.25) (end 0.5 0.25)
      (stroke (width 0.15) (type solid)) (fill none) (layer "F.Fab"))
    (pad "1" smd roundrect (at -0.48 0) (size 0.59 0.64) (layers "F.Cu" "F.Paste" "F.Mask") (roundrect_rratio 0.25)
      (net 784 "Net-(U15-FB)") (pintype "passive"))
    (pad "2" smd roundrect (at 0.48 0) (size 0.59 0.64) (layers "F.Cu" "F.Paste" "F.Mask") (roundrect_rratio 0.25)
      (net 1 "GND") (pintype "passive"))
  )
	(footprint "antmicro-footprints:C_0402_1005Metric" (layer "F.Cu")
    (at 82 66.95 -90)
    (descr "Capacitor SMD 0402")
    (tags "capacitor SMD 0402")
    (property "Author" "Antmicro")
    (property "Dielectric" "X5R")
    (property "License" "Apache-2.0")
    (property "MPN" "GRM155R61H104KE14D")
    (property "Manufacturer" "Murata")
    (property "Public" "False")
    (property "Sheetfile" "power-supply.kicad_sch")
    (property "Sheetname" "Power supply")
    (property "Val" "100n")
    (property "Voltage" "50V")
    (property "ki_description" "SMD Multilayer Ceramic Capacitor, 0.1 µF, 50 V, 0402 [1005 Metric], ± 10%, X5R, GRM Series")
    (property "ki_keywords" "0402, SMT, CAPACITOR, PASSIVE, CERAMIC, MLCC")
    (attr smd)
    (fp_text reference "C105" (at 2.145 0.21 -90) (layer "F.SilkS")
        (effects (font (size 0.7 0.7) (thickness 0.127)))
    )
    (fp_text value "C_100n_0402" (at 0 1.17 90) (layer "F.Fab")
        (effects (font (size 1 1) (thickness 0.15)))
    )
    (fp_text user "${REFERENCE}" (at 0 0 90) (layer "F.Fab")
        (effects (font (size 0.25 0.25) (thickness 0.04)))
    )
    (fp_text user "Author: Antmicro" (at -0.939 3.399 -90) (layer "F.Fab") hide
        (effects (font (size 0.7 0.7) (thickness 0.15)) (justify left bottom))
    )
    (fp_text user "License: Apache-2.0" (at -0.939 5.799 -90) (layer "F.Fab") hide
        (effects (font (size 0.7 0.7) (thickness 0.15)) (justify left bottom))
    )
    (fp_rect (start -0.925 -0.47) (end 0.925 0.47)
      (stroke (width 0.05) (type default)) (fill none) (layer "F.CrtYd"))
    (fp_line (start -0.494 -0.25) (end 0.504 -0.25)
      (stroke (width 0.15) (type solid)) (layer "F.Fab"))
    (fp_line (start -0.494 0.248) (end -0.494 -0.25)
      (stroke (width 0.15) (type solid)) (layer "F.Fab"))
    (fp_line (start 0.504 -0.25) (end 0.504 0.248)
      (stroke (width 0.15) (type solid)) (layer "F.Fab"))
    (fp_line (start 0.504 0.248) (end -0.494 0.248)
      (stroke (width 0.15) (type solid)) (layer "F.Fab"))
    (pad "1" smd roundrect (at -0.48 0 270) (size 0.59 0.64) (layers "F.Cu" "F.Paste" "F.Mask") (roundrect_rratio 0.25)
      (net 782 "Net-(U15-BOOT)") (pintype "passive"))
    (pad "2" smd roundrect (at 0.48 0 270) (size 0.59 0.64) (layers "F.Cu" "F.Paste" "F.Mask") (roundrect_rratio 0.25)
      (net 265 "Net-(D6-C)") (pintype "passive"))
  )
	(footprint "antmicro-footprints:R_0402_1005Metric" (layer "F.Cu")
    (at 80.33 62.305)
    (descr "Resistor SMD 0402")
    (tags "resistor SMD 0402")
    (property "Author" "Antmicro")
    (property "License" "Apache-2.0")
    (property "MPN" "CR0402-FX-2433GLF")
    (property "Manufacturer" "Bourns")
    (property "Public" "False")
    (property "Sheetfile" "power-supply.kicad_sch")
    (property "Sheetname" "Power supply")
    (property "Tolerance" "1%")
    (property "Val" "243k")
    (property "ki_description" "SMD Chip Resistor")
    (property "ki_keywords" "0402, SMT, RESISTOR, PASSIVE")
    (attr smd)
    (fp_text reference "R91" (at 0.03 -0.93) (layer "F.SilkS")
        (effects (font (size 0.7 0.7) (thickness 0.127)))
    )
    (fp_text value "R_243k_0402" (at 0 1.17) (layer "F.Fab")
        (effects (font (size 1 1) (thickness 0.15)))
    )
    (fp_text user "${REFERENCE}" (at 0 0) (layer "F.Fab")
        (effects (font (size 0.25 0.25) (thickness 0.04)))
    )
    (fp_text user "License: Apache-2.0" (at -0.95 5.169) (layer "F.Fab") hide
        (effects (font (size 0.7 0.7) (thickness 0.15)) (justify left bottom))
    )
    (fp_text user "Author: Antmicro" (at -0.95 4.169) (layer "F.Fab") hide
        (effects (font (size 0.7 0.7) (thickness 0.15)) (justify left bottom))
    )
    (fp_rect (start -0.925 -0.47) (end 0.925 0.47)
      (stroke (width 0.05) (type default)) (fill none) (layer "F.CrtYd"))
    (fp_rect (start -0.5 -0.25) (end 0.5 0.25)
      (stroke (width 0.15) (type solid)) (fill none) (layer "F.Fab"))
    (pad "1" smd roundrect (at -0.48 0) (size 0.59 0.64) (layers "F.Cu" "F.Paste" "F.Mask") (roundrect_rratio 0.25)
      (net 1 "GND") (pintype "passive"))
    (pad "2" smd roundrect (at 0.48 0) (size 0.59 0.64) (layers "F.Cu" "F.Paste" "F.Mask") (roundrect_rratio 0.25)
      (net 783 "Net-(U15-RT{slash}CLK)") (pintype "passive"))
  )
	(footprint "antmicro-footprints:R_0402_1005Metric" (layer "F.Cu")
    (at 72.7 77.75 180)
    (descr "Resistor SMD 0402")
    (tags "resistor SMD 0402")
    (property "Author" "Antmicro")
    (property "Current" "1A")
    (property "License" "Apache-2.0")
    (property "MPN" "ERJ2GE0R00X")
    (property "Manufacturer" "Panasonic")
    (property "Public" "False")
    (property "Sheetfile" "power-supply.kicad_sch")
    (property "Sheetname" "Power supply")
    (property "Tolerance" "")
    (property "Val" "0R")
    (property "ki_description" "SMD Chip Resistor, Jumper, 0 ohm, 100 mW, 0402 [1005 Metric], Thick Film, General Purpose")
    (property "ki_keywords" "0402, SMT, RESISTOR, PASSIVE")
    (attr smd)
    (fp_text reference "R137" (at 3.07 -0.61) (layer "F.SilkS")
        (effects (font (size 0.7 0.7) (thickness 0.127)))
    )
    (fp_text value "R_0R_0402" (at 0 1.17) (layer "F.Fab")
        (effects (font (size 1 1) (thickness 0.15)))
    )
    (fp_text user "License: Apache-2.0" (at -0.95 5.169 180) (layer "F.Fab") hide
        (effects (font (size 0.7 0.7) (thickness 0.15)) (justify left bottom))
    )
    (fp_text user "Author: Antmicro" (at -0.95 4.169 180) (layer "F.Fab") hide
        (effects (font (size 0.7 0.7) (thickness 0.15)) (justify left bottom))
    )
    (fp_text user "${REFERENCE}" (at 0 0) (layer "F.Fab")
        (effects (font (size 0.25 0.25) (thickness 0.04)))
    )
    (fp_rect (start -0.925 -0.47) (end 0.925 0.47)
      (stroke (width 0.05) (type default)) (fill none) (layer "F.CrtYd"))
    (fp_rect (start -0.5 -0.25) (end 0.5 0.25)
      (stroke (width 0.15) (type solid)) (fill none) (layer "F.Fab"))
    (pad "1" smd roundrect (at -0.48 0 180) (size 0.59 0.64) (layers "F.Cu" "F.Paste" "F.Mask") (roundrect_rratio 0.25)
      (net 419 "Net-(U12-FLAG1)") (pintype "passive"))
    (pad "2" smd roundrect (at 0.48 0 180) (size 0.59 0.64) (layers "F.Cu" "F.Paste" "F.Mask") (roundrect_rratio 0.25)
      (net 366 "/Power supply/VCCA0_EN") (pintype "passive"))
  )
	(footprint "antmicro-footprints:R_0402_1005Metric" (layer "F.Cu")
    (at 72.7 76.7 180)
    (descr "Resistor SMD 0402")
    (tags "resistor SMD 0402")
    (property "Author" "Antmicro")
    (property "Current" "1A")
    (property "License" "Apache-2.0")
    (property "MPN" "ERJ2GE0R00X")
    (property "Manufacturer" "Panasonic")
    (property "Public" "False")
    (property "Sheetfile" "power-supply.kicad_sch")
    (property "Sheetname" "Power supply")
    (property "Tolerance" "")
    (property "Val" "0R")
    (property "ki_description" "SMD Chip Resistor, Jumper, 0 ohm, 100 mW, 0402 [1005 Metric], Thick Film, General Purpose")
    (property "ki_keywords" "0402, SMT, RESISTOR, PASSIVE")
    (attr smd)
    (fp_text reference "R138" (at 3.07 -0.61) (layer "F.SilkS")
        (effects (font (size 0.7 0.7) (thickness 0.127)))
    )
    (fp_text value "R_0R_0402" (at 0 1.17) (layer "F.Fab")
        (effects (font (size 1 1) (thickness 0.15)))
    )
    (fp_text user "License: Apache-2.0" (at -0.95 5.169 180) (layer "F.Fab") hide
        (effects (font (size 0.7 0.7) (thickness 0.15)) (justify left bottom))
    )
    (fp_text user "${REFERENCE}" (at 0 0) (layer "F.Fab")
        (effects (font (size 0.25 0.25) (thickness 0.04)))
    )
    (fp_text user "Author: Antmicro" (at -0.95 4.169 180) (layer "F.Fab") hide
        (effects (font (size 0.7 0.7) (thickness 0.15)) (justify left bottom))
    )
    (fp_rect (start -0.925 -0.47) (end 0.925 0.47)
      (stroke (width 0.05) (type default)) (fill none) (layer "F.CrtYd"))
    (fp_rect (start -0.5 -0.25) (end 0.5 0.25)
      (stroke (width 0.15) (type solid)) (fill none) (layer "F.Fab"))
    (pad "1" smd roundrect (at -0.48 0 180) (size 0.59 0.64) (layers "F.Cu" "F.Paste" "F.Mask") (roundrect_rratio 0.25)
      (net 420 "Net-(U12-FLAG2)") (pintype "passive"))
    (pad "2" smd roundrect (at 0.48 0 180) (size 0.59 0.64) (layers "F.Cu" "F.Paste" "F.Mask") (roundrect_rratio 0.25)
      (net 231 "/Power supply/VCCIO_EN") (pintype "passive"))
  )
	(footprint "antmicro-footprints:R_0402_1005Metric" (layer "F.Cu")
    (at 72.7 75.65 180)
    (descr "Resistor SMD 0402")
    (tags "resistor SMD 0402")
    (property "Author" "Antmicro")
    (property "Current" "1A")
    (property "License" "Apache-2.0")
    (property "MPN" "ERJ2GE0R00X")
    (property "Manufacturer" "Panasonic")
    (property "Public" "False")
    (property "Sheetfile" "power-supply.kicad_sch")
    (property "Sheetname" "Power supply")
    (property "Tolerance" "")
    (property "Val" "0R")
    (property "ki_description" "SMD Chip Resistor, Jumper, 0 ohm, 100 mW, 0402 [1005 Metric], Thick Film, General Purpose")
    (property "ki_keywords" "0402, SMT, RESISTOR, PASSIVE")
    (attr smd)
    (fp_text reference "R139" (at 3.07 -0.61) (layer "F.SilkS")
        (effects (font (size 0.7 0.7) (thickness 0.127)))
    )
    (fp_text value "R_0R_0402" (at 0 1.17) (layer "F.Fab")
        (effects (font (size 1 1) (thickness 0.15)))
    )
    (fp_text user "${REFERENCE}" (at 0 0) (layer "F.Fab")
        (effects (font (size 0.25 0.25) (thickness 0.04)))
    )
    (fp_text user "License: Apache-2.0" (at -0.95 5.169 180) (layer "F.Fab") hide
        (effects (font (size 0.7 0.7) (thickness 0.15)) (justify left bottom))
    )
    (fp_text user "Author: Antmicro" (at -0.95 4.169 180) (layer "F.Fab") hide
        (effects (font (size 0.7 0.7) (thickness 0.15)) (justify left bottom))
    )
    (fp_rect (start -0.925 -0.47) (end 0.925 0.47)
      (stroke (width 0.05) (type default)) (fill none) (layer "F.CrtYd"))
    (fp_rect (start -0.5 -0.25) (end 0.5 0.25)
      (stroke (width 0.15) (type solid)) (fill none) (layer "F.Fab"))
    (pad "1" smd roundrect (at -0.48 0 180) (size 0.59 0.64) (layers "F.Cu" "F.Paste" "F.Mask") (roundrect_rratio 0.25)
      (net 422 "Net-(U12-FLAG3)") (pintype "passive"))
    (pad "2" smd roundrect (at 0.48 0 180) (size 0.59 0.64) (layers "F.Cu" "F.Paste" "F.Mask") (roundrect_rratio 0.25)
      (net 230 "/Power supply/VCCAUX_EN") (pintype "passive"))
  )
	(footprint "antmicro-footprints:C_0402_1005Metric" (layer "F.Cu")
    (at 76.24 73.64 -90)
    (descr "Capacitor SMD 0402")
    (tags "capacitor SMD 0402")
    (property "Author" "Antmicro")
    (property "Dielectric" "X7R")
    (property "License" "Apache-2.0")
    (property "MPN" "GRM155R71H103KA88D")
    (property "Manufacturer" "Murata")
    (property "Public" "False")
    (property "Sheetfile" "power-supply.kicad_sch")
    (property "Sheetname" "Power supply")
    (property "Val" "10n")
    (property "Voltage" "50V")
    (property "ki_description" "SMD Multilayer Ceramic Capacitor, 10000 pF, 50 V, 0402 [1005 Metric], ± 10%, X7R, GRM Series")
    (property "ki_keywords" "0402, SMT, CAPACITOR, PASSIVE")
    (attr smd)
    (fp_text reference "C95" (at -0.095 1.54 90) (layer "F.SilkS")
        (effects (font (size 0.7 0.7) (thickness 0.127)))
    )
    (fp_text value "C_10n_0402" (at 0 1.17 90) (layer "F.Fab")
        (effects (font (size 1 1) (thickness 0.15)))
    )
    (fp_text user "Author: Antmicro" (at -0.939 3.399 -90) (layer "F.Fab") hide
        (effects (font (size 0.7 0.7) (thickness 0.15)) (justify left bottom))
    )
    (fp_text user "${REFERENCE}" (at 0 0 90) (layer "F.Fab")
        (effects (font (size 0.25 0.25) (thickness 0.04)))
    )
    (fp_text user "License: Apache-2.0" (at -0.939 5.799 -90) (layer "F.Fab") hide
        (effects (font (size 0.7 0.7) (thickness 0.15)) (justify left bottom))
    )
    (fp_rect (start -0.925 -0.47) (end 0.925 0.47)
      (stroke (width 0.05) (type default)) (fill none) (layer "F.CrtYd"))
    (fp_line (start -0.494 -0.25) (end 0.504 -0.25)
      (stroke (width 0.15) (type solid)) (layer "F.Fab"))
    (fp_line (start -0.494 0.248) (end -0.494 -0.25)
      (stroke (width 0.15) (type solid)) (layer "F.Fab"))
    (fp_line (start 0.504 -0.25) (end 0.504 0.248)
      (stroke (width 0.15) (type solid)) (layer "F.Fab"))
    (fp_line (start 0.504 0.248) (end -0.494 0.248)
      (stroke (width 0.15) (type solid)) (layer "F.Fab"))
    (pad "1" smd roundrect (at -0.48 0 270) (size 0.59 0.64) (layers "F.Cu" "F.Paste" "F.Mask") (roundrect_rratio 0.25)
      (net 1 "GND") (pintype "passive"))
    (pad "2" smd roundrect (at 0.48 0 270) (size 0.59 0.64) (layers "F.Cu" "F.Paste" "F.Mask") (roundrect_rratio 0.25)
      (net 229 "Net-(U12-TADJ)") (pintype "passive"))
  )
)
